# S9S_MB_2U (Grand Teton) — schematic netlist excerpt (pin names and nets, part order shuffled) for the footprints in the layout excerpt that follows; sources: Cadence DE-HDL packaged netlist, KiCad conversion of 03242023_DA0F0TMBIJ0_F0T_Motherboard_J_brd_V01_OCP.brd

R1693  Q_RES  33.2 1% CHIP  pkg 0402LF  page 244 : A = PWRGD_DSW_PWROK_R2 ; B = PWRGD_DSW_PWROK
PC1525  Q_CAP  1UF 25V 10% X6S  pkg C0402  page 302 : A = HSC_VDD_R_1 ; B = AGND_HSC

(kicad_pcb
	(version 20260206)
	(generator "pcbnew")
	(generator_version "10.0")
	(general
		(thickness 1.6)
		(legacy_teardrops no)
	)
	(paper "A4")
	(title_block
		(title "03242023_DA0F0TMBIJ0_F0T_Motherboard_J_brd_V01_OCP.brd")
		(comment 1 "Grand Teton / footprints 3-4 of 6105")
	)
	(layers
		(0 "F.Cu" signal "TOP")
		(4 "In1.Cu" signal "GND")
		(6 "In2.Cu" signal "IN1")
		(8 "In3.Cu" signal "GND1")
		(10 "In4.Cu" signal "IN2")
		(12 "In5.Cu" signal "GND2")
		(14 "In6.Cu" signal "IN3")
		(16 "In7.Cu" signal "GND3")
		(18 "In8.Cu" signal "VCC")
		(20 "In9.Cu" signal "VCC1")
		(22 "In10.Cu" signal "GND4")
		(24 "In11.Cu" signal "IN4")
		(26 "In12.Cu" signal "GND5")
		(28 "In13.Cu" signal "IN5")
		(30 "In14.Cu" signal "GND6")
		(32 "In15.Cu" signal "IN6")
		(34 "In16.Cu" signal "GND7")
		(2 "B.Cu" signal "BOTTOM")
		(9 "F.Adhes" user "F.Adhesive")
		(11 "B.Adhes" user "B.Adhesive")
		(13 "F.Paste" user "Package Geometry/Pastemask Top")
		(15 "B.Paste" user "Package Geometry/Pastemask Bottom")
		(5 "F.SilkS" user "Ref Des/Silkscreen Top")
		(7 "B.SilkS" user "Ref Des/Silkscreen Bottom")
		(1 "F.Mask" user "Board Geometry/Soldermask Top")
		(3 "B.Mask" user "Board Geometry/Soldermask Bottom")
		(17 "Dwgs.User" user "User.Drawings")
		(19 "Cmts.User" user "User.Comments")
		(21 "Eco1.User" user "User.Eco1")
		(23 "Eco2.User" user "User.Eco2")
		(25 "Edge.Cuts" user "Board Geometry/Outline")
		(27 "Margin" user)
		(31 "F.CrtYd" user "Package Geometry/Place Bound Top")
		(29 "B.CrtYd" user "Package Geometry/Place Bound Bottom")
		(35 "F.Fab" user "Ref Des/Assembly Top")
		(33 "B.Fab" user "Ref Des/Assembly Bottom")
	)
	(footprint ""
		(layer "F.Cu")
		(at 209.74558 -128.544828 180)
		(property "Reference" "R1693"
			(at 0 0 180)
			(layer "F.SilkS")
			(hide yes)
			(effects
				(font
					(size 1.27 1.27)
				)
			)
		)
		(property "Value" ""
			(at 0 0 180)
			(layer "F.Fab")
			(effects
				(font
					(size 1.27 1.27)
				)
			)
		)
		(duplicate_pad_numbers_are_jumpers no)
		(fp_line
			(start 0.7874 0.4064)
			(end -0.7874 0.4064)
			(stroke
				(width 0.1524)
				(type default)
			)
			(layer "F.SilkS")
		)
		(fp_line
			(start 0.7874 -0.4064)
			(end 0.7874 0.4064)
			(stroke
				(width 0.1524)
				(type default)
			)
			(layer "F.SilkS")
		)
		(fp_line
			(start -0.7874 0.4064)
			(end -0.7874 -0.4064)
			(stroke
				(width 0.1524)
				(type default)
			)
			(layer "F.SilkS")
		)
		(fp_line
			(start -0.7874 -0.4064)
			(end 0.7874 -0.4064)
			(stroke
				(width 0.1524)
				(type default)
			)
			(layer "F.SilkS")
		)
		(fp_line
			(start 0.67945 0.3048)
			(end 0.120396 0.3048)
			(stroke
				(width 0.1)
				(type default)
			)
			(layer "F.Fab")
		)
		(fp_line
			(start 0.67945 -0.3048)
			(end 0.67945 0.3048)
			(stroke
				(width 0.1)
				(type default)
			)
			(layer "F.Fab")
		)
		(fp_line
			(start 0.12065 -0.2794)
			(end 0.12065 -0.3048)
			(stroke
				(width 0.1)
				(type default)
			)
			(layer "F.Fab")
		)
		(fp_line
			(start 0.12065 -0.3048)
			(end 0.67945 -0.3048)
			(stroke
				(width 0.1)
				(type default)
			)
			(layer "F.Fab")
		)
		(fp_line
			(start 0.120396 0.3048)
			(end 0.120396 0.2794)
			(stroke
				(width 0.1)
				(type default)
			)
			(layer "F.Fab")
		)
		(fp_line
			(start 0.120396 0.2794)
			(end -0.12065 0.2794)
			(stroke
				(width 0.1)
				(type default)
			)
			(layer "F.Fab")
		)
		(fp_line
			(start -0.12065 0.3048)
			(end -0.67945 0.3048)
			(stroke
				(width 0.1)
				(type default)
			)
			(layer "F.Fab")
		)
		(fp_line
			(start -0.12065 0.2794)
			(end -0.12065 0.3048)
			(stroke
				(width 0.1)
				(type default)
			)
			(layer "F.Fab")
		)
		(fp_line
			(start -0.12065 -0.2794)
			(end 0.12065 -0.2794)
			(stroke
				(width 0.1)
				(type default)
			)
			(layer "F.Fab")
		)
		(fp_line
			(start -0.12065 -0.305054)
			(end -0.12065 -0.2794)
			(stroke
				(width 0.1)
				(type default)
			)
			(layer "F.Fab")
		)
		(fp_line
			(start -0.67945 0.3048)
			(end -0.67945 -0.305054)
			(stroke
				(width 0.1)
				(type default)
			)
			(layer "F.Fab")
		)
		(fp_line
			(start -0.67945 -0.305054)
			(end -0.12065 -0.305054)
			(stroke
				(width 0.1)
				(type default)
			)
			(layer "F.Fab")
		)
		(pad "1" smd circle
			(at -0.40005 0 180)
			(size 0 0)
			(layers "F.Cu" "F.Mask" "F.Paste")
			(net "PWRGD_DSW_PWROK_R2")
		)
		(pad "2" smd circle
			(at 0.40005 0 180)
			(size 0 0)
			(layers "F.Cu" "F.Mask" "F.Paste")
			(net "PWRGD_DSW_PWROK")
		)
	)
	(footprint ""
		(layer "F.Cu")
		(at 196.329808 -402.766022 90)
		(property "Reference" "PC1525"
			(at 0 0 90)
			(layer "F.SilkS")
			(hide yes)
			(effects
				(font
					(size 1.27 1.27)
				)
			)
		)
		(property "Value" ""
			(at 0 0 90)
			(layer "F.Fab")
			(effects
				(font
					(size 1.27 1.27)
				)
			)
		)
		(duplicate_pad_numbers_are_jumpers no)
		(fp_line
			(start 0.7874 -0.4064)
			(end 0.7874 0.4064)
			(stroke
				(width 0.1524)
				(type default)
			)
			(layer "F.SilkS")
		)
		(fp_line
			(start -0.7874 -0.4064)
			(end 0.7874 -0.4064)
			(stroke
				(width 0.1524)
				(type default)
			)
			(layer "F.SilkS")
		)
		(fp_line
			(start 0.7874 0.4064)
			(end -0.7874 0.4064)
			(stroke
				(width 0.1524)
				(type default)
			)
			(layer "F.SilkS")
		)
		(fp_line
			(start -0.7874 0.4064)
			(end -0.7874 -0.4064)
			(stroke
				(width 0.1524)
				(type default)
			)
			(layer "F.SilkS")
		)
		(fp_line
			(start -0.12065 -0.305054)
			(end -0.12065 -0.2794)
			(stroke
				(width 0.1)
				(type default)
			)
			(layer "F.Fab")
		)
		(fp_line
			(start -0.67945 -0.305054)
			(end -0.12065 -0.305054)
			(stroke
				(width 0.1)
				(type default)
			)
			(layer "F.Fab")
		)
		(fp_line
			(start 0.67945 -0.3048)
			(end 0.67945 0.3048)
			(stroke
				(width 0.1)
				(type default)
			)
			(layer "F.Fab")
		)
		(fp_line
			(start 0.12065 -0.3048)
			(end 0.67945 -0.3048)
			(stroke
				(width 0.1)
				(type default)
			)
			(layer "F.Fab")
		)
		(fp_line
			(start 0.12065 -0.2794)
			(end 0.12065 -0.3048)
			(stroke
				(width 0.1)
				(type default)
			)
			(layer "F.Fab")
		)
		(fp_line
			(start -0.12065 -0.2794)
			(end 0.12065 -0.2794)
			(stroke
				(width 0.1)
				(type default)
			)
			(layer "F.Fab")
		)
		(fp_line
			(start 0.120396 0.2794)
			(end -0.12065 0.2794)
			(stroke
				(width 0.1)
				(type default)
			)
			(layer "F.Fab")
		)
		(fp_line
			(start -0.12065 0.2794)
			(end -0.12065 0.3048)
			(stroke
				(width 0.1)
				(type default)
			)
			(layer "F.Fab")
		)
		(fp_line
			(start 0.67945 0.3048)
			(end 0.120396 0.3048)
			(stroke
				(width 0.1)
				(type default)
			)
			(layer "F.Fab")
		)
		(fp_line
			(start 0.120396 0.3048)
			(end 0.120396 0.2794)
			(stroke
				(width 0.1)
				(type default)
			)
			(layer "F.Fab")
		)
		(fp_line
			(start -0.12065 0.3048)
			(end -0.67945 0.3048)
			(stroke
				(width 0.1)
				(type default)
			)
			(layer "F.Fab")
		)
		(fp_line
			(start -0.67945 0.3048)
			(end -0.67945 -0.305054)
			(stroke
				(width 0.1)
				(type default)
			)
			(layer "F.Fab")
		)
		(pad "1" smd circle
			(at -0.40005 0 90)
			(size 0 0)
			(layers "F.Cu" "F.Mask" "F.Paste")
			(net "HSC_VDD_R_1")
		)
		(pad "2" smd circle
			(at 0.40005 0 90)
			(size 0 0)
			(layers "F.Cu" "F.Mask" "F.Paste")
			(net "AGND_HSC")
		)
	)
)
